# T6G (Grand Teton) — schematic netlist excerpt (pin names and nets, part order shuffled) for the footprints in the layout excerpt that follows; sources: Cadence DE-HDL packaged netlist, KiCad conversion of 04192023_DAF0TMB3IC0_F0TG_MB_C_brd_V02_OCP.brd

PU299  RS31312R  IC  pkg QFN22_TH_3X5  page 152
  EN  = P12V_SCM_EN_R2
  LOADEN  = GND
  ENTM  = GND
  TIMER  = P12V_SCM_TIMER
  ISET  = P12V_SCM_ISET
  SS  = P12V_SCM_SS
  GND  = GND
  IMON  = P12V_SCM_IMON
  FLTB  = P12V_SCM_FLTB_N
  PG  = HP_LVC3_SCM_HSC_PWRGD_R
  OV  = P12V_SCM_OV_FB
  AVIN  = P12V_SCM_AVIN_PD
  VOUT_13  = P12V_SCM_R
  VOUT_14  = P12V_SCM_R
  VOUT_15  = P12V_SCM_R
  VOUT_16  = P12V_SCM_R
  VOUT_17  = P12V_SCM_R
  VOUT_18  = P12V_SCM_R
  VOUT_19  = P12V_SCM_R
  VOUT_20  = P12V_SCM_R
  VIN_21_22  = P12V_AUX
  VIN_23  = P12V_AUX
  VIN_24  = P12V_AUX
  VIN_25  = P12V_AUX
  VIN_26  = P12V_AUX

(kicad_pcb
	(version 20260206)
	(generator "pcbnew")
	(generator_version "10.0")
	(general
		(thickness 1.6)
		(legacy_teardrops no)
	)
	(paper "A4")
	(title_block
		(title "04192023_DAF0TMB3IC0_F0TG_MB_C_brd_V02_OCP.brd")
		(comment 1 "Grand Teton / footprint 3355 of 8354 (PU299), pads 1-25 of 25")
	)
	(layers
		(0 "F.Cu" signal "TOP")
		(4 "In1.Cu" signal "GND")
		(6 "In2.Cu" signal "IN1")
		(8 "In3.Cu" signal "GND1")
		(10 "In4.Cu" signal "IN2")
		(12 "In5.Cu" signal "GND2")
		(14 "In6.Cu" signal "IN3")
		(16 "In7.Cu" signal "GND3")
		(18 "In8.Cu" signal "VCC")
		(20 "In9.Cu" signal "VCC1")
		(22 "In10.Cu" signal "GND4")
		(24 "In11.Cu" signal "IN4")
		(26 "In12.Cu" signal "GND5")
		(28 "In13.Cu" signal "IN5")
		(30 "In14.Cu" signal "GND6")
		(32 "In15.Cu" signal "IN6")
		(34 "In16.Cu" signal "GND7")
		(2 "B.Cu" signal "BOTTOM")
		(9 "F.Adhes" user "F.Adhesive")
		(11 "B.Adhes" user "B.Adhesive")
		(13 "F.Paste" user "Package Geometry/Pastemask Top")
		(15 "B.Paste" user "Package Geometry/Pastemask Bottom")
		(5 "F.SilkS" user "Ref Des/Silkscreen Top")
		(7 "B.SilkS" user "Ref Des/Silkscreen Bottom")
		(1 "F.Mask" user "Board Geometry/Soldermask Top")
		(3 "B.Mask" user "Board Geometry/Soldermask Bottom")
		(17 "Dwgs.User" user "User.Drawings")
		(19 "Cmts.User" user "User.Comments")
		(21 "Eco1.User" user "User.Eco1")
		(23 "Eco2.User" user "User.Eco2")
		(25 "Edge.Cuts" user "Board Geometry/Outline")
		(27 "Margin" user)
		(31 "F.CrtYd" user "Package Geometry/Place Bound Top")
		(29 "B.CrtYd" user "Package Geometry/Place Bound Bottom")
		(35 "F.Fab" user "Ref Des/Assembly Top")
		(33 "B.Fab" user "Ref Des/Assembly Bottom")
	)
	(footprint ""
		(layer "F.Cu")
		(at 177.694082 -28.937712 -90)
		(property "Reference" "PU299"
			(at -4.293616 -3.376676 0)
			(unlocked yes)
			(layer "F.SilkS")
			(effects
				(font
					(size 0.7874 0.5842)
					(thickness 0.1524)
				)
				(justify left)
			)
		)
		(property "Value" ""
			(at 0 0 270)
			(layer "F.Fab")
			(effects
				(font
					(size 1.27 1.27)
				)
			)
		)
		(duplicate_pad_numbers_are_jumpers no)
		(pad "1" smd circle
			(at -1.374902 -1.999996 180)
			(size 0 0)
			(layers "F.Cu" "F.Mask" "F.Paste")
			(net "P12V_SCM_EN_R2")
		)
		(pad "2" smd rect
			(at -1.400048 -1.500124 180)
			(size 0.254 0.8128)
			(layers "F.Cu" "F.Mask" "F.Paste")
			(net "GND")
		)
		(pad "3" smd rect
			(at -1.400048 -0.999998 180)
			(size 0.254 0.8128)
			(layers "F.Cu" "F.Mask" "F.Paste")
			(net "GND")
		)
		(pad "4" smd rect
			(at -1.400048 -0.499872 180)
			(size 0.254 0.8128)
			(layers "F.Cu" "F.Mask" "F.Paste")
			(net "P12V_SCM_TIMER")
		)
		(pad "5" smd rect
			(at -1.400048 0 180)
			(size 0.254 0.8128)
			(layers "F.Cu" "F.Mask" "F.Paste")
			(net "P12V_SCM_ISET")
		)
		(pad "6" smd rect
			(at -1.400048 0.499872 180)
			(size 0.254 0.8128)
			(layers "F.Cu" "F.Mask" "F.Paste")
			(net "P12V_SCM_SS")
		)
		(pad "7" smd rect
			(at -1.400048 0.999998 180)
			(size 0.254 0.8128)
			(layers "F.Cu" "F.Mask" "F.Paste")
			(net "GND")
		)
		(pad "8" smd rect
			(at -1.400048 1.500124 180)
			(size 0.254 0.8128)
			(layers "F.Cu" "F.Mask" "F.Paste")
			(net "P12V_SCM_IMON")
		)
		(pad "9" smd rect
			(at -1.400048 1.999996 180)
			(size 0.254 0.8128)
			(layers "F.Cu" "F.Mask" "F.Paste")
			(net "P12V_SCM_FLTB_N")
		)
		(pad "10" smd rect
			(at -0.499872 2.400046 270)
			(size 0.254 0.8128)
			(layers "F.Cu" "F.Mask" "F.Paste")
			(net "HP_LVC3_SCM_HSC_PWRGD_R")
		)
		(pad "11" smd rect
			(at 0.499872 2.400046 270)
			(size 0.254 0.8128)
			(layers "F.Cu" "F.Mask" "F.Paste")
			(net "P12V_SCM_OV_FB")
		)
		(pad "12" smd rect
			(at 1.400048 1.999996 180)
			(size 0.254 0.8128)
			(layers "F.Cu" "F.Mask" "F.Paste")
			(net "P12V_SCM_AVIN_PD")
		)
		(pad "13" smd rect
			(at 1.400048 1.500124 180)
			(size 0.254 0.8128)
			(layers "F.Cu" "F.Mask" "F.Paste")
			(net "P12V_SCM_R")
		)
		(pad "14" smd rect
			(at 1.400048 0.999998 180)
			(size 0.254 0.8128)
			(layers "F.Cu" "F.Mask" "F.Paste")
			(net "P12V_SCM_R")
		)
		(pad "15" smd rect
			(at 1.400048 0.499872 180)
			(size 0.254 0.8128)
			(layers "F.Cu" "F.Mask" "F.Paste")
			(net "P12V_SCM_R")
		)
		(pad "16" smd rect
			(at 1.400048 0 180)
			(size 0.254 0.8128)
			(layers "F.Cu" "F.Mask" "F.Paste")
			(net "P12V_SCM_R")
		)
		(pad "17" smd rect
			(at 1.400048 -0.499872 180)
			(size 0.254 0.8128)
			(layers "F.Cu" "F.Mask" "F.Paste")
			(net "P12V_SCM_R")
		)
		(pad "18" smd rect
			(at 1.400048 -0.999998 180)
			(size 0.254 0.8128)
			(layers "F.Cu" "F.Mask" "F.Paste")
			(net "P12V_SCM_R")
		)
		(pad "19" smd rect
			(at 1.400048 -1.500124 180)
			(size 0.254 0.8128)
			(layers "F.Cu" "F.Mask" "F.Paste")
			(net "P12V_SCM_R")
		)
		(pad "20" smd rect
			(at 1.400048 -1.999996 180)
			(size 0.254 0.8128)
			(layers "F.Cu" "F.Mask" "F.Paste")
			(net "P12V_SCM_R")
		)
		(pad "21_22" smd circle
			(at 0.499872 -2.337562 180)
			(size 0 0)
			(layers "F.Cu" "F.Mask" "F.Paste")
			(net "P12V_AUX")
		)
		(pad "23" smd rect
			(at 0 -1.100074 180)
			(size 0.254 1.27)
			(layers "F.Cu" "F.Mask" "F.Paste")
			(net "P12V_AUX")
		)
		(pad "24" smd rect
			(at 0 -0.199898 180)
			(size 0.254 1.27)
			(layers "F.Cu" "F.Mask" "F.Paste")
			(net "P12V_AUX")
		)
		(pad "25" smd rect
			(at 0 0.700024 180)
			(size 0.254 1.27)
			(layers "F.Cu" "F.Mask" "F.Paste")
			(net "P12V_AUX")
		)
		(pad "26" smd rect
			(at 0 1.599946 180)
			(size 0.254 1.27)
			(layers "F.Cu" "F.Mask" "F.Paste")
			(net "P12V_AUX")
		)
	)
)
